FILE_TYPE = MULTI_PHYS_TABLE;
PART 'CONN3_G98259001'
{================================================================================================================================================================}
:PACK_TYPE | MATERIAL | PART_NUMBER     = EnvComp                  |PART_NUMBER   |JEDEC_TYPE            |CLASS  |DESCRIPTION                           |HEIGHT      |COMPONENT_TYPE  |LEAD_LENGTH | SPEED_URL | Status |RPL| AML | Bus_Unit | Days ;
{================================================================================================================================================================}
'THMT'     | 'CONN'   | 'G98259-001'(!) = 'YES;YES;YES;UNK;ok;VLD' | 'G98259-001' | 'CONN3_G98259001'    | 'IO'  | 'CONN_HDR,3X1,PLG,RA,11.75mm,6ST,MT' | '0.396 IN' | 'THMT'         | '0.157'    | 'http://speed.intel.com:8081/speed/module/pdm/item/pdm_item_detail_direct.asp?item_cde=G98259-001&item_rev=01&url_param=unused' | 'Design' | 'NO' | '1' | 'SMO_BOARDS' | '???' 
'THMT'     | 'EMPTY'  | 'G98259-001'(!) = 'YES;YES;YES;UNK;ok;VLD' | 'G98259-001' | 'CONN3_G98259001'    | 'IO'  | 'CONN_HDR,3X1,PLG,RA,11.75mm,6ST,MT' | '0.396 IN' | 'THMT'         | '0.157'    | 'http://speed.intel.com:8081/speed/module/pdm/item/pdm_item_detail_direct.asp?item_cde=G98259-001&item_rev=01&url_param=unused' | 'Design' | 'NO' | '1' | 'SMO_BOARDS' | '???' 
'PIP'      | 'CONN'   | 'G98259-001'(!) = 'YES;YES;YES;UNK;ok;VLD' | 'G98259-001' | 'CONN3_G98259001_PIP'| 'IO'  | 'CONN_HDR,3X1,PLG,RA,11.75mm,6ST,MT' | '0.396 IN' | 'THMT'         | '0.157'    | 'http://speed.intel.com:8081/speed/module/pdm/item/pdm_item_detail_direct.asp?item_cde=G98259-001&item_rev=01&url_param=unused' | 'Design' | 'NO' | '1' | 'SMO_BOARDS' | '???' 
'PIP'      | 'EMPTY'  | 'G98259-001'(!) = 'YES;YES;YES;UNK;ok;VLD' | 'G98259-001' | 'CONN3_G98259001_PIP'| 'IO'  | 'CONN_HDR,3X1,PLG,RA,11.75mm,6ST,MT' | '0.396 IN' | 'THMT'         | '0.157'    | 'http://speed.intel.com:8081/speed/module/pdm/item/pdm_item_detail_direct.asp?item_cde=G98259-001&item_rev=01&url_param=unused' | 'Design' | 'NO' | '1' | 'SMO_BOARDS' | '???' 
END_PART
END.
